(kicad_pcb
	(version 20260206)
	(generator "pcbnew")
	(generator_version "10.0")
	(general
		(thickness 1.6)
		(legacy_teardrops no)
	)
	(paper "A4")
	(title_block
		(title "04192023_DAF0TMB3IC0_F0TG_MB_C_brd_V02_OCP.brd")
		(comment 1 "Grand Teton / footprints 2018-2023 of 8354")
	)
	(layers
		(0 "F.Cu" signal "TOP")
		(4 "In1.Cu" signal "GND")
		(6 "In2.Cu" signal "IN1")
		(8 "In3.Cu" signal "GND1")
		(10 "In4.Cu" signal "IN2")
		(12 "In5.Cu" signal "GND2")
		(14 "In6.Cu" signal "IN3")
		(16 "In7.Cu" signal "GND3")
		(18 "In8.Cu" signal "VCC")
		(20 "In9.Cu" signal "VCC1")
		(22 "In10.Cu" signal "GND4")
		(24 "In11.Cu" signal "IN4")
		(26 "In12.Cu" signal "GND5")
		(28 "In13.Cu" signal "IN5")
		(30 "In14.Cu" signal "GND6")
		(32 "In15.Cu" signal "IN6")
		(34 "In16.Cu" signal "GND7")
		(2 "B.Cu" signal "BOTTOM")
		(9 "F.Adhes" user "F.Adhesive")
		(11 "B.Adhes" user "B.Adhesive")
		(13 "F.Paste" user "Package Geometry/Pastemask Top")
		(15 "B.Paste" user "Package Geometry/Pastemask Bottom")
		(5 "F.SilkS" user "Ref Des/Silkscreen Top")
		(7 "B.SilkS" user "Ref Des/Silkscreen Bottom")
		(1 "F.Mask" user "Board Geometry/Soldermask Top")
		(3 "B.Mask" user "Board Geometry/Soldermask Bottom")
		(17 "Dwgs.User" user "User.Drawings")
		(19 "Cmts.User" user "User.Comments")
		(21 "Eco1.User" user "User.Eco1")
		(23 "Eco2.User" user "User.Eco2")
		(25 "Edge.Cuts" user "Board Geometry/Outline")
		(27 "Margin" user)
		(31 "F.CrtYd" user "Package Geometry/Place Bound Top")
		(29 "B.CrtYd" user "Package Geometry/Place Bound Bottom")
		(35 "F.Fab" user "Ref Des/Assembly Top")
		(33 "B.Fab" user "Ref Des/Assembly Bottom")
	)
	(footprint ""
		(layer "F.Cu")
		(at 253.063756 -418.11067 -90)
		(property "Reference" "PD13"
			(at -1.69926 -3.99034 90)
			(unlocked yes)
			(layer "F.SilkS")
			(effects
				(font
					(size 0.7874 0.5842)
					(thickness 0.1524)
				)
				(justify left)
			)
		)
		(property "Value" ""
			(at 0 0 270)
			(layer "F.Fab")
			(effects
				(font
					(size 1.27 1.27)
				)
			)
		)
		(duplicate_pad_numbers_are_jumpers no)
		(fp_line
			(start -4.664456 3.109976)
			(end -4.664456 -3.109976)
			(stroke
				(width 0.1524)
				(type default)
			)
			(layer "F.SilkS")
		)
		(fp_line
			(start 4.156202 3.109976)
			(end 4.183126 3.109976)
			(stroke
				(width 0.1524)
				(type default)
			)
			(layer "F.SilkS")
		)
		(fp_line
			(start 4.743704 3.109976)
			(end 4.6101 3.109976)
			(stroke
				(width 0.1524)
				(type default)
			)
			(layer "F.SilkS")
		)
		(fp_line
			(start 4.743704 3.109976)
			(end 5.4102 3.109976)
			(stroke
				(width 0.1524)
				(type default)
			)
			(layer "F.SilkS")
		)
		(fp_line
			(start 4.769104 3.109976)
			(end -4.664456 3.109976)
			(stroke
				(width 0.1524)
				(type default)
			)
			(layer "F.SilkS")
		)
		(fp_line
			(start 4.794504 3.109976)
			(end 3.554984 3.109976)
			(stroke
				(width 0.1524)
				(type default)
			)
			(layer "F.SilkS")
		)
		(fp_line
			(start 5.4102 3.109976)
			(end 5.4102 -3.109976)
			(stroke
				(width 0.1524)
				(type default)
			)
			(layer "F.SilkS")
		)
		(fp_line
			(start 4.715002 3.035554)
			(end 4.7117 2.984754)
			(stroke
				(width 0.1524)
				(type default)
			)
			(layer "F.SilkS")
		)
		(fp_line
			(start 0.762 1.27)
			(end 0.762 -1.27)
			(stroke
				(width 0.1524)
				(type default)
			)
			(layer "F.SilkS")
		)
		(fp_line
			(start -0.508 1.016)
			(end -0.508 -1.016)
			(stroke
				(width 0.1524)
				(type default)
			)
			(layer "F.SilkS")
		)
		(fp_line
			(start -1.0668 0)
			(end -0.6096 0)
			(stroke
				(width 0.1524)
				(type default)
			)
			(layer "F.SilkS")
		)
		(fp_line
			(start 0.762 0)
			(end -0.508 1.016)
			(stroke
				(width 0.1524)
				(type default)
			)
			(layer "F.SilkS")
		)
		(fp_line
			(start 0.762 0)
			(end 1.2192 0)
			(stroke
				(width 0.1524)
				(type default)
			)
			(layer "F.SilkS")
		)
		(fp_line
			(start -0.508 -1.016)
			(end 0.762 0)
			(stroke
				(width 0.1524)
				(type default)
			)
			(layer "F.SilkS")
		)
		(fp_line
			(start -4.664456 -3.109976)
			(end 4.743704 -3.109976)
			(stroke
				(width 0.1524)
				(type default)
			)
			(layer "F.SilkS")
		)
		(fp_line
			(start 4.183126 -3.109976)
			(end 4.794504 -3.109976)
			(stroke
				(width 0.1524)
				(type default)
			)
			(layer "F.SilkS")
		)
		(fp_line
			(start 4.511802 -3.109976)
			(end 4.207002 -3.109976)
			(stroke
				(width 0.1524)
				(type default)
			)
			(layer "F.SilkS")
		)
		(fp_line
			(start 4.6101 -3.109976)
			(end 4.283202 -3.109976)
			(stroke
				(width 0.1524)
				(type default)
			)
			(layer "F.SilkS")
		)
		(fp_line
			(start 4.695444 -3.109976)
			(end 4.695444 3.109976)
			(stroke
				(width 0.1524)
				(type default)
			)
			(layer "F.SilkS")
		)
		(fp_line
			(start 4.70535 -3.109976)
			(end 4.70535 3.109976)
			(stroke
				(width 0.1524)
				(type default)
			)
			(layer "F.SilkS")
		)
		(fp_line
			(start 4.70535 -3.109976)
			(end 4.70535 3.109976)
			(stroke
				(width 0.1524)
				(type default)
			)
			(layer "F.SilkS")
		)
		(fp_line
			(start 4.70535 -3.109976)
			(end 4.70535 3.109976)
			(stroke
				(width 0.1524)
				(type default)
			)
			(layer "F.SilkS")
		)
		(fp_line
			(start 4.805426 -3.109976)
			(end 4.805426 3.109976)
			(stroke
				(width 0.1524)
				(type default)
			)
			(layer "F.SilkS")
		)
		(fp_line
			(start 4.932426 -3.109976)
			(end 4.932426 3.109976)
			(stroke
				(width 0.1524)
				(type default)
			)
			(layer "F.SilkS")
		)
		(fp_line
			(start 5.008626 -3.109976)
			(end 5.008626 3.109976)
			(stroke
				(width 0.1524)
				(type default)
			)
			(layer "F.SilkS")
		)
		(fp_line
			(start 5.110226 -3.109976)
			(end 5.110226 3.109976)
			(stroke
				(width 0.1524)
				(type default)
			)
			(layer "F.SilkS")
		)
		(fp_line
			(start 5.211826 -3.109976)
			(end 5.211826 3.109976)
			(stroke
				(width 0.1524)
				(type default)
			)
			(layer "F.SilkS")
		)
		(fp_line
			(start 5.262626 -3.109976)
			(end 5.262626 3.109976)
			(stroke
				(width 0.1524)
				(type default)
			)
			(layer "F.SilkS")
		)
		(fp_line
			(start 5.313426 -3.109976)
			(end 5.313426 3.109976)
			(stroke
				(width 0.1524)
				(type default)
			)
			(layer "F.SilkS")
		)
		(fp_line
			(start 5.4102 -3.109976)
			(end 4.783074 -3.109976)
			(stroke
				(width 0.1524)
				(type default)
			)
			(layer "F.SilkS")
		)
		(fp_line
			(start -4.065016 3.109976)
			(end -4.065016 -3.109976)
			(stroke
				(width 0.1)
				(type default)
			)
			(layer "F.Fab")
		)
		(fp_line
			(start 4.065016 3.109976)
			(end -4.065016 3.109976)
			(stroke
				(width 0.1)
				(type default)
			)
			(layer "F.Fab")
		)
		(fp_line
			(start -4.065016 -3.109976)
			(end 4.065016 -3.109976)
			(stroke
				(width 0.1)
				(type default)
			)
			(layer "F.Fab")
		)
		(fp_line
			(start 4.065016 -3.109976)
			(end 4.065016 3.109976)
			(stroke
				(width 0.1)
				(type default)
			)
			(layer "F.Fab")
		)
		(fp_text user "-"
			(at 6.643624 0.40005 90)
			(unlocked yes)
			(layer "F.SilkS")
			(effects
				(font
					(size 1.905 1.4224)
					(thickness 0.1524)
				)
				(justify left)
			)
		)
		(fp_text user "+"
			(at -4.5974 0.24765 90)
			(unlocked yes)
			(layer "F.SilkS")
			(effects
				(font
					(size 1.905 1.4224)
					(thickness 0.1524)
				)
				(justify left)
			)
		)
		(fp_text user "-"
			(at 6.643624 0.40005 90)
			(unlocked yes)
			(layer "F.Fab")
			(effects
				(font
					(size 1.905 1.4224)
					(thickness 0.1524)
				)
				(justify left)
			)
		)
		(fp_text user "+"
			(at -4.5974 0.24765 90)
			(unlocked yes)
			(layer "F.Fab")
			(effects
				(font
					(size 1.905 1.4224)
					(thickness 0.1524)
				)
				(justify left)
			)
		)
		(pad "A" smd rect
			(at -3.299968 0 90)
			(size 2.413 3.302)
			(layers "F.Cu" "F.Mask" "F.Paste")
			(net "GND")
		)
		(pad "C" smd rect
			(at 3.299968 0 90)
			(size 2.413 3.302)
			(layers "F.Cu" "F.Mask" "F.Paste")
			(net "P12V_PSU_FUSE")
		)
	)
	(footprint ""
		(layer "F.Cu")
		(at 117.094 -417.957 90)
		(property "Reference" "C1802"
			(at 0 0 90)
			(layer "F.SilkS")
			(hide yes)
			(effects
				(font
					(size 1.27 1.27)
				)
			)
		)
		(property "Value" ""
			(at 0 0 90)
			(layer "F.Fab")
			(effects
				(font
					(size 1.27 1.27)
				)
			)
		)
		(duplicate_pad_numbers_are_jumpers no)
		(fp_line
			(start 0.7874 -0.4064)
			(end 0.7874 0.4064)
			(stroke
				(width 0.1524)
				(type default)
			)
			(layer "F.SilkS")
		)
		(fp_line
			(start -0.7874 -0.4064)
			(end 0.7874 -0.4064)
			(stroke
				(width 0.1524)
				(type default)
			)
			(layer "F.SilkS")
		)
		(fp_line
			(start 0.7874 0.4064)
			(end -0.7874 0.4064)
			(stroke
				(width 0.1524)
				(type default)
			)
			(layer "F.SilkS")
		)
		(fp_line
			(start -0.7874 0.4064)
			(end -0.7874 -0.4064)
			(stroke
				(width 0.1524)
				(type default)
			)
			(layer "F.SilkS")
		)
		(fp_line
			(start -0.12065 -0.305054)
			(end -0.12065 -0.2794)
			(stroke
				(width 0.1)
				(type default)
			)
			(layer "F.Fab")
		)
		(fp_line
			(start -0.67945 -0.305054)
			(end -0.12065 -0.305054)
			(stroke
				(width 0.1)
				(type default)
			)
			(layer "F.Fab")
		)
		(fp_line
			(start 0.67945 -0.3048)
			(end 0.67945 0.3048)
			(stroke
				(width 0.1)
				(type default)
			)
			(layer "F.Fab")
		)
		(fp_line
			(start 0.12065 -0.3048)
			(end 0.67945 -0.3048)
			(stroke
				(width 0.1)
				(type default)
			)
			(layer "F.Fab")
		)
		(fp_line
			(start 0.12065 -0.2794)
			(end 0.12065 -0.3048)
			(stroke
				(width 0.1)
				(type default)
			)
			(layer "F.Fab")
		)
		(fp_line
			(start -0.12065 -0.2794)
			(end 0.12065 -0.2794)
			(stroke
				(width 0.1)
				(type default)
			)
			(layer "F.Fab")
		)
		(fp_line
			(start 0.120396 0.2794)
			(end -0.12065 0.2794)
			(stroke
				(width 0.1)
				(type default)
			)
			(layer "F.Fab")
		)
		(fp_line
			(start -0.12065 0.2794)
			(end -0.12065 0.3048)
			(stroke
				(width 0.1)
				(type default)
			)
			(layer "F.Fab")
		)
		(fp_line
			(start 0.67945 0.3048)
			(end 0.120396 0.3048)
			(stroke
				(width 0.1)
				(type default)
			)
			(layer "F.Fab")
		)
		(fp_line
			(start 0.120396 0.3048)
			(end 0.120396 0.2794)
			(stroke
				(width 0.1)
				(type default)
			)
			(layer "F.Fab")
		)
		(fp_line
			(start -0.12065 0.3048)
			(end -0.67945 0.3048)
			(stroke
				(width 0.1)
				(type default)
			)
			(layer "F.Fab")
		)
		(fp_line
			(start -0.67945 0.3048)
			(end -0.67945 -0.305054)
			(stroke
				(width 0.1)
				(type default)
			)
			(layer "F.Fab")
		)
		(pad "1" smd circle
			(at -0.40005 0 90)
			(size 0 0)
			(layers "F.Cu" "F.Mask" "F.Paste")
			(net "FM_SMB_1_ALERT_GPU_ISO_N")
		)
		(pad "2" smd circle
			(at 0.40005 0 90)
			(size 0 0)
			(layers "F.Cu" "F.Mask" "F.Paste")
			(net "GND")
		)
	)
	(footprint ""
		(layer "F.Cu")
		(at 215.4301 -400.972782 180)
		(property "Reference" "PR3986"
			(at 0 0 180)
			(layer "F.SilkS")
			(hide yes)
			(effects
				(font
					(size 1.27 1.27)
				)
			)
		)
		(property "Value" ""
			(at 0 0 180)
			(layer "F.Fab")
			(effects
				(font
					(size 1.27 1.27)
				)
			)
		)
		(duplicate_pad_numbers_are_jumpers no)
		(fp_line
			(start 0.7874 0.4064)
			(end -0.7874 0.4064)
			(stroke
				(width 0.1524)
				(type default)
			)
			(layer "F.SilkS")
		)
		(fp_line
			(start 0.7874 -0.4064)
			(end 0.7874 0.4064)
			(stroke
				(width 0.1524)
				(type default)
			)
			(layer "F.SilkS")
		)
		(fp_line
			(start -0.7874 0.4064)
			(end -0.7874 -0.4064)
			(stroke
				(width 0.1524)
				(type default)
			)
			(layer "F.SilkS")
		)
		(fp_line
			(start -0.7874 -0.4064)
			(end 0.7874 -0.4064)
			(stroke
				(width 0.1524)
				(type default)
			)
			(layer "F.SilkS")
		)
		(fp_line
			(start 0.67945 0.3048)
			(end 0.120396 0.3048)
			(stroke
				(width 0.1)
				(type default)
			)
			(layer "F.Fab")
		)
		(fp_line
			(start 0.67945 -0.3048)
			(end 0.67945 0.3048)
			(stroke
				(width 0.1)
				(type default)
			)
			(layer "F.Fab")
		)
		(fp_line
			(start 0.12065 -0.2794)
			(end 0.12065 -0.3048)
			(stroke
				(width 0.1)
				(type default)
			)
			(layer "F.Fab")
		)
		(fp_line
			(start 0.12065 -0.3048)
			(end 0.67945 -0.3048)
			(stroke
				(width 0.1)
				(type default)
			)
			(layer "F.Fab")
		)
		(fp_line
			(start 0.120396 0.3048)
			(end 0.120396 0.2794)
			(stroke
				(width 0.1)
				(type default)
			)
			(layer "F.Fab")
		)
		(fp_line
			(start 0.120396 0.2794)
			(end -0.12065 0.2794)
			(stroke
				(width 0.1)
				(type default)
			)
			(layer "F.Fab")
		)
		(fp_line
			(start -0.12065 0.3048)
			(end -0.67945 0.3048)
			(stroke
				(width 0.1)
				(type default)
			)
			(layer "F.Fab")
		)
		(fp_line
			(start -0.12065 0.2794)
			(end -0.12065 0.3048)
			(stroke
				(width 0.1)
				(type default)
			)
			(layer "F.Fab")
		)
		(fp_line
			(start -0.12065 -0.2794)
			(end 0.12065 -0.2794)
			(stroke
				(width 0.1)
				(type default)
			)
			(layer "F.Fab")
		)
		(fp_line
			(start -0.12065 -0.305054)
			(end -0.12065 -0.2794)
			(stroke
				(width 0.1)
				(type default)
			)
			(layer "F.Fab")
		)
		(fp_line
			(start -0.67945 0.3048)
			(end -0.67945 -0.305054)
			(stroke
				(width 0.1)
				(type default)
			)
			(layer "F.Fab")
		)
		(fp_line
			(start -0.67945 -0.305054)
			(end -0.12065 -0.305054)
			(stroke
				(width 0.1)
				(type default)
			)
			(layer "F.Fab")
		)
		(pad "1" smd circle
			(at -0.40005 0 180)
			(size 0 0)
			(layers "F.Cu" "F.Mask" "F.Paste")
			(net "HSC_CS_3")
		)
		(pad "2" smd circle
			(at 0.40005 0 180)
			(size 0 0)
			(layers "F.Cu" "F.Mask" "F.Paste")
			(net "AGND_HSC")
		)
	)
	(footprint ""
		(layer "F.Cu")
		(at 120.523 -321.691 90)
		(property "Reference" "R8351"
			(at 0 0 90)
			(layer "F.SilkS")
			(hide yes)
			(effects
				(font
					(size 1.27 1.27)
				)
			)
		)
		(property "Value" ""
			(at 0 0 90)
			(layer "F.Fab")
			(effects
				(font
					(size 1.27 1.27)
				)
			)
		)
		(duplicate_pad_numbers_are_jumpers no)
		(fp_line
			(start 0.7874 -0.4064)
			(end 0.7874 -0.0762)
			(stroke
				(width 0.1524)
				(type default)
			)
			(layer "F.SilkS")
		)
		(fp_line
			(start -0.7874 -0.4064)
			(end 0.7874 -0.4064)
			(stroke
				(width 0.1524)
				(type default)
			)
			(layer "F.SilkS")
		)
		(fp_line
			(start -0.7874 -0.0254)
			(end -0.7874 -0.4064)
			(stroke
				(width 0.1524)
				(type default)
			)
			(layer "F.SilkS")
		)
		(fp_line
			(start 0.4064 0.4064)
			(end -0.381 0.4064)
			(stroke
				(width 0.1524)
				(type default)
			)
			(layer "F.SilkS")
		)
		(fp_line
			(start -0.12065 -0.305054)
			(end -0.12065 -0.2794)
			(stroke
				(width 0.1)
				(type default)
			)
			(layer "F.Fab")
		)
		(fp_line
			(start -0.67945 -0.305054)
			(end -0.12065 -0.305054)
			(stroke
				(width 0.1)
				(type default)
			)
			(layer "F.Fab")
		)
		(fp_line
			(start 0.67945 -0.3048)
			(end 0.67945 0.3048)
			(stroke
				(width 0.1)
				(type default)
			)
			(layer "F.Fab")
		)
		(fp_line
			(start 0.12065 -0.3048)
			(end 0.67945 -0.3048)
			(stroke
				(width 0.1)
				(type default)
			)
			(layer "F.Fab")
		)
		(fp_line
			(start 0.12065 -0.2794)
			(end 0.12065 -0.3048)
			(stroke
				(width 0.1)
				(type default)
			)
			(layer "F.Fab")
		)
		(fp_line
			(start -0.12065 -0.2794)
			(end 0.12065 -0.2794)
			(stroke
				(width 0.1)
				(type default)
			)
			(layer "F.Fab")
		)
		(fp_line
			(start 0.120396 0.2794)
			(end -0.12065 0.2794)
			(stroke
				(width 0.1)
				(type default)
			)
			(layer "F.Fab")
		)
		(fp_line
			(start -0.12065 0.2794)
			(end -0.12065 0.3048)
			(stroke
				(width 0.1)
				(type default)
			)
			(layer "F.Fab")
		)
		(fp_line
			(start 0.67945 0.3048)
			(end 0.120396 0.3048)
			(stroke
				(width 0.1)
				(type default)
			)
			(layer "F.Fab")
		)
		(fp_line
			(start 0.120396 0.3048)
			(end 0.120396 0.2794)
			(stroke
				(width 0.1)
				(type default)
			)
			(layer "F.Fab")
		)
		(fp_line
			(start -0.12065 0.3048)
			(end -0.67945 0.3048)
			(stroke
				(width 0.1)
				(type default)
			)
			(layer "F.Fab")
		)
		(fp_line
			(start -0.67945 0.3048)
			(end -0.67945 -0.305054)
			(stroke
				(width 0.1)
				(type default)
			)
			(layer "F.Fab")
		)
		(pad "1" smd circle
			(at -0.40005 0 90)
			(size 0 0)
			(layers "F.Cu" "F.Mask" "F.Paste")
			(net "CLK_100M_CPU1_CLK13_R_DN")
		)
		(pad "2" smd circle
			(at 0.40005 0 90)
			(size 0 0)
			(layers "F.Cu" "F.Mask" "F.Paste")
			(net "CLK_100M_CPU1_CLK13_DN")
		)
	)
	(footprint ""
		(layer "F.Cu")
		(at 371.298724 -435.600094)
		(property "Reference" "H128"
			(at -5.98043 -4.94538 0)
			(unlocked yes)
			(layer "F.SilkS")
			(effects
				(font
					(size 0.7874 0.5842)
					(thickness 0.1524)
				)
				(justify left)
			)
		)
		(property "Value" ""
			(at 0 0 0)
			(layer "F.Fab")
			(effects
				(font
					(size 1.27 1.27)
				)
			)
		)
		(duplicate_pad_numbers_are_jumpers no)
		(pad "1" thru_hole circle
			(at 0 0)
			(size 10.0076 10.0076)
			(drill 5.6134)
			(layers "*.Cu" "*.Mask")
			(remove_unused_layers no)
			(net "GND")
			(clearance -1.9431)
		)
	)
	(footprint ""
		(layer "F.Cu")
		(at 63.059564 -16.220948 -90)
		(property "Reference" "R3169"
			(at 0 0 270)
			(layer "F.SilkS")
			(hide yes)
			(effects
				(font
					(size 1.27 1.27)
				)
			)
		)
		(property "Value" ""
			(at 0 0 270)
			(layer "F.Fab")
			(effects
				(font
					(size 1.27 1.27)
				)
			)
		)
		(duplicate_pad_numbers_are_jumpers no)
		(fp_line
			(start -0.7874 0.4064)
			(end -0.7874 -0.4064)
			(stroke
				(width 0.1524)
				(type default)
			)
			(layer "F.SilkS")
		)
		(fp_line
			(start 0.7874 0.4064)
			(end -0.7874 0.4064)
			(stroke
				(width 0.1524)
				(type default)
			)
			(layer "F.SilkS")
		)
		(fp_line
			(start -0.7874 -0.4064)
			(end 0.7874 -0.4064)
			(stroke
				(width 0.1524)
				(type default)
			)
			(layer "F.SilkS")
		)
		(fp_line
			(start 0.7874 -0.4064)
			(end 0.7874 0.4064)
			(stroke
				(width 0.1524)
				(type default)
			)
			(layer "F.SilkS")
		)
		(fp_line
			(start -0.67945 0.3048)
			(end -0.67945 -0.305054)
			(stroke
				(width 0.1)
				(type default)
			)
			(layer "F.Fab")
		)
		(fp_line
			(start -0.12065 0.3048)
			(end -0.67945 0.3048)
			(stroke
				(width 0.1)
				(type default)
			)
			(layer "F.Fab")
		)
		(fp_line
			(start 0.120396 0.3048)
			(end 0.120396 0.2794)
			(stroke
				(width 0.1)
				(type default)
			)
			(layer "F.Fab")
		)
		(fp_line
			(start 0.67945 0.3048)
			(end 0.120396 0.3048)
			(stroke
				(width 0.1)
				(type default)
			)
			(layer "F.Fab")
		)
		(fp_line
			(start -0.12065 0.2794)
			(end -0.12065 0.3048)
			(stroke
				(width 0.1)
				(type default)
			)
			(layer "F.Fab")
		)
		(fp_line
			(start 0.120396 0.2794)
			(end -0.12065 0.2794)
			(stroke
				(width 0.1)
				(type default)
			)
			(layer "F.Fab")
		)
		(fp_line
			(start -0.12065 -0.2794)
			(end 0.12065 -0.2794)
			(stroke
				(width 0.1)
				(type default)
			)
			(layer "F.Fab")
		)
		(fp_line
			(start 0.12065 -0.2794)
			(end 0.12065 -0.3048)
			(stroke
				(width 0.1)
				(type default)
			)
			(layer "F.Fab")
		)
		(fp_line
			(start 0.12065 -0.3048)
			(end 0.67945 -0.3048)
			(stroke
				(width 0.1)
				(type default)
			)
			(layer "F.Fab")
		)
		(fp_line
			(start 0.67945 -0.3048)
			(end 0.67945 0.3048)
			(stroke
				(width 0.1)
				(type default)
			)
			(layer "F.Fab")
		)
		(fp_line
			(start -0.67945 -0.305054)
			(end -0.12065 -0.305054)
			(stroke
				(width 0.1)
				(type default)
			)
			(layer "F.Fab")
		)
		(fp_line
			(start -0.12065 -0.305054)
			(end -0.12065 -0.2794)
			(stroke
				(width 0.1)
				(type default)
			)
			(layer "F.Fab")
		)
		(pad "1" smd circle
			(at -0.40005 0 270)
			(size 0 0)
			(layers "F.Cu" "F.Mask" "F.Paste")
			(net "OCP_V3_2_ISO_BIF0_EN")
		)
		(pad "2" smd circle
			(at 0.40005 0 270)
			(size 0 0)
			(layers "F.Cu" "F.Mask" "F.Paste")
			(net "OCP_V3_2_BIF0_R_N")
		)
	)
)
